# BASEBOARD_FAB2 (Tioga Pass) — schematic netlist excerpt (pin names and nets, part order shuffled) for the footprints in the layout excerpt that follows; sources: Cadence DE-HDL packaged netlist, KiCad conversion of Wiwynn_Tioga_Pass_MB.brd

R9G12  RES  20.0 1% CHIP  pkg 0402  page 159 : A = SMB_OCP_LAN_STBY_LVC3_SDA ; B = SMB_SPRINGVILLE_STBY_LVC3_SDA

Q7E6  FET_N_DUAL  NTJD4001N FET  pkg SMLF  page 95
  SOURCE(0)  = GND
  GATE(0)  = IRQ_CPU1_PROCHOT_G_N
  DRAIN(0)  = H_CPU1_PROCHOT_G_N
  SOURCE(0)  = GND
  GATE(0)  = IRQ_CPU1_VRHOT
  DRAIN(0)  = IRQ_CPU1_VRHOT

(kicad_pcb
	(version 20260206)
	(generator "pcbnew")
	(generator_version "10.0")
	(general
		(thickness 1.6)
		(legacy_teardrops no)
	)
	(paper "A4")
	(title_block
		(title "Wiwynn_Tioga_Pass_MB.brd")
		(comment 1 "Tioga Pass / footprints 3355-3356 of 4770")
	)
	(layers
		(0 "F.Cu" signal "TOP")
		(4 "In1.Cu" signal "L2GND")
		(6 "In2.Cu" signal "L3")
		(8 "In3.Cu" signal "L4GND")
		(10 "In4.Cu" signal "L5")
		(12 "In5.Cu" signal "L6GND")
		(14 "In6.Cu" signal "L7VCC")
		(16 "In7.Cu" signal "L8VCC")
		(18 "In8.Cu" signal "L9GND")
		(20 "In9.Cu" signal "L10")
		(22 "In10.Cu" signal "L11GND")
		(24 "In11.Cu" signal "L12")
		(26 "In12.Cu" signal "L13GND")
		(2 "B.Cu" signal "BOTTOM")
		(9 "F.Adhes" user "F.Adhesive")
		(11 "B.Adhes" user "B.Adhesive")
		(13 "F.Paste" user "Package Geometry/Pastemask Top")
		(15 "B.Paste" user "Package Geometry/Pastemask Bottom")
		(5 "F.SilkS" user "Ref Des/Silkscreen Top")
		(7 "B.SilkS" user "Ref Des/Silkscreen Bottom")
		(1 "F.Mask" user "Board Geometry/Soldermask Top")
		(3 "B.Mask" user "Board Geometry/Soldermask Bottom")
		(17 "Dwgs.User" user "User.Drawings")
		(19 "Cmts.User" user "User.Comments")
		(21 "Eco1.User" user "User.Eco1")
		(23 "Eco2.User" user "User.Eco2")
		(25 "Edge.Cuts" user "Board Geometry/Outline")
		(27 "Margin" user)
		(31 "F.CrtYd" user "Package Geometry/Place Bound Top")
		(29 "B.CrtYd" user "Package Geometry/Place Bound Bottom")
		(35 "F.Fab" user "Ref Des/Assembly Top")
		(33 "B.Fab" user "Ref Des/Assembly Bottom")
	)
	(footprint ""
		(layer "B.Cu")
		(at 380.746 -46.0883 180)
		(property "Reference" "Q7E6"
			(at 1.17475 1.7907 90)
			(unlocked yes)
			(layer "B.SilkS")
			(effects
				(font
					(size 0.7874 0.5842)
					(thickness 0.1524)
				)
				(justify left mirror)
			)
		)
		(property "Value" ""
			(at 0 0 0)
			(layer "B.Fab")
			(effects
				(font
					(size 1.27 1.27)
				)
				(justify mirror)
			)
		)
		(duplicate_pad_numbers_are_jumpers no)
		(fp_circle
			(center 0.508 -0.7874)
			(end 0.381 -0.7874)
			(stroke
				(width 0.254)
				(type default)
			)
			(fill no)
			(layer "B.SilkS")
		)
		(fp_poly
			(pts
				(xy -0.2159 1.7526) (xy -1.5621 1.7526) (xy -1.5621 -0.4572) (xy -0.2159 -0.4572)
			)
			(stroke
				(width 0)
				(type default)
			)
			(fill no)
			(layer "B.CrtYd")
		)
		(fp_line
			(start -0.2159 1.75514)
			(end -1.5621 1.75514)
			(stroke
				(width 0.1)
				(type default)
			)
			(layer "B.Fab")
		)
		(fp_line
			(start -0.2159 -0.45466)
			(end -0.2159 1.75514)
			(stroke
				(width 0.1)
				(type default)
			)
			(layer "B.Fab")
		)
		(fp_line
			(start -1.5621 1.75514)
			(end -1.5621 -0.45466)
			(stroke
				(width 0.1)
				(type default)
			)
			(layer "B.Fab")
		)
		(fp_line
			(start -1.5621 -0.45466)
			(end -0.2159 -0.45466)
			(stroke
				(width 0.1)
				(type default)
			)
			(layer "B.Fab")
		)
		(fp_circle
			(center 0.508 -0.7874)
			(end 0.381 -0.7874)
			(stroke
				(width 0.254)
				(type default)
			)
			(fill no)
			(layer "B.Fab")
		)
		(pad "1" smd rect
			(at 0 0)
			(size 1.016 0.381)
			(layers "B.Cu" "B.Mask" "B.Paste")
			(net "GND")
		)
		(pad "2" smd rect
			(at 0 0.65024)
			(size 1.016 0.381)
			(layers "B.Cu" "B.Mask" "B.Paste")
			(net "IRQ_CPU1_PROCHOT_G_N")
		)
		(pad "3" smd rect
			(at 0 1.30048)
			(size 1.016 0.381)
			(layers "B.Cu" "B.Mask" "B.Paste")
			(net "H_CPU1_PROCHOT_G_N")
		)
		(pad "4" smd rect
			(at -1.778 1.30048)
			(size 1.016 0.381)
			(layers "B.Cu" "B.Mask" "B.Paste")
			(net "GND")
		)
		(pad "5" smd rect
			(at -1.778 0.65024)
			(size 1.016 0.381)
			(layers "B.Cu" "B.Mask" "B.Paste")
			(net "IRQ_CPU1_VRHOT")
		)
		(pad "6" smd rect
			(at -1.778 0)
			(size 1.016 0.381)
			(layers "B.Cu" "B.Mask" "B.Paste")
			(net "IRQ_CPU1_VRHOT")
		)
		(zone
			(layer "B.Cu")
			(hatch none 0.5)
			(connect_pads
				(clearance 0)
			)
			(min_thickness 0.25)
			(keepout
				(tracks allowed)
				(vias not_allowed)
				(pads allowed)
				(copperpour not_allowed)
				(footprints allowed)
			)
			(placement
				(enabled no)
				(sheetname "")
			)
			(fill
				(thermal_gap 0.5)
				(thermal_bridge_width 0.5)
				(island_removal_mode 0)
			)
			(polygon
				(pts
					(xy 380.238 -45.8978) (xy 381.254 -45.8978) (xy 381.254 -47.5869) (xy 380.238 -47.5869)
				)
			)
		)
		(zone
			(layer "B.Cu")
			(hatch none 0.5)
			(connect_pads
				(clearance 0)
			)
			(min_thickness 0.25)
			(keepout
				(tracks allowed)
				(vias not_allowed)
				(pads allowed)
				(copperpour not_allowed)
				(footprints allowed)
			)
			(placement
				(enabled no)
				(sheetname "")
			)
			(fill
				(thermal_gap 0.5)
				(thermal_bridge_width 0.5)
				(island_removal_mode 0)
			)
			(polygon
				(pts
					(xy 382.016 -45.8978) (xy 383.032 -45.8978) (xy 383.032 -47.5869) (xy 382.016 -47.5869)
				)
			)
		)
	)
	(footprint ""
		(layer "B.Cu")
		(at 490.3851 -121.5136 90)
		(property "Reference" "R9G12"
			(at 0 0 90)
			(layer "B.SilkS")
			(hide yes)
			(effects
				(font
					(size 1.27 1.27)
				)
				(justify mirror)
			)
		)
		(property "Value" ""
			(at 0 0 90)
			(layer "B.Fab")
			(effects
				(font
					(size 1.27 1.27)
				)
				(justify mirror)
			)
		)
		(duplicate_pad_numbers_are_jumpers no)
		(fp_poly
			(pts
				(xy 0.2794 -0.1016) (xy -0.2794 -0.1016) (xy -0.2794 0.9906) (xy 0.2794 0.9906)
			)
			(stroke
				(width 0)
				(type default)
			)
			(fill no)
			(layer "B.CrtYd")
		)
		(fp_line
			(start 0.2794 -0.1016)
			(end 0.2794 0.9906)
			(stroke
				(width 0.1)
				(type default)
			)
			(layer "B.Fab")
		)
		(fp_line
			(start -0.2794 -0.1016)
			(end 0.2794 -0.1016)
			(stroke
				(width 0.1)
				(type default)
			)
			(layer "B.Fab")
		)
		(fp_line
			(start 0.2794 0.9906)
			(end -0.2794 0.9906)
			(stroke
				(width 0.1)
				(type default)
			)
			(layer "B.Fab")
		)
		(fp_line
			(start -0.2794 0.9906)
			(end -0.2794 -0.1016)
			(stroke
				(width 0.1)
				(type default)
			)
			(layer "B.Fab")
		)
		(pad "1" smd rect
			(at 0 0 270)
			(size 0.508 0.508)
			(layers "B.Cu" "B.Mask" "B.Paste")
			(net "SMB_OCP_LAN_STBY_LVC3_SDA")
		)
		(pad "2" smd rect
			(at 0 0.889 270)
			(size 0.508 0.508)
			(layers "B.Cu" "B.Mask" "B.Paste")
			(net "SMB_SPRINGVILLE_STBY_LVC3_SDA")
		)
		(zone
			(layer "B.Cu")
			(hatch none 0.5)
			(connect_pads
				(clearance 0)
			)
			(min_thickness 0.25)
			(keepout
				(tracks allowed)
				(vias not_allowed)
				(pads allowed)
				(copperpour not_allowed)
				(footprints allowed)
			)
			(placement
				(enabled no)
				(sheetname "")
			)
			(fill
				(thermal_gap 0.5)
				(thermal_bridge_width 0.5)
				(island_removal_mode 0)
			)
			(polygon
				(pts
					(xy 490.6391 -121.7676) (xy 490.6391 -121.2596) (xy 491.0201 -121.2596) (xy 491.0201 -121.7676)
				)
			)
		)
		(zone
			(layer "B.Cu")
			(hatch none 0.5)
			(connect_pads
				(clearance 0)
			)
			(min_thickness 0.25)
			(keepout
				(tracks not_allowed)
				(vias allowed)
				(pads allowed)
				(copperpour not_allowed)
				(footprints allowed)
			)
			(placement
				(enabled no)
				(sheetname "")
			)
			(fill
				(thermal_gap 0.5)
				(thermal_bridge_width 0.5)
				(island_removal_mode 0)
			)
			(polygon
				(pts
					(xy 491.0201 -121.7676) (xy 491.0201 -121.2596) (xy 490.6391 -121.2596) (xy 490.6391 -121.7676)
				)
			)
		)
	)
)
